FILE_TYPE = CONNECTIVITY;
{Allegro Design Entry HDL 17.4-2019 S026 (4007227) 1/17/2022}
"PAGE_NUMBER" = 191;
0"NC";
1"GND\g";
2"GND\g";
3"GND\g";
4"GND\g";
5"GND\g";
6"GND\g";
7"SW_PVDDCR_SOC_P1_BOOT3";
8"SW_PVDDCR_SOC_P1_PH3";
9"SW_PVDDCR_SOC_P1_SW3";
10"PVDDCR_SOC_P1_VOS3";
11"NC_PVDDCR_SOC_P1_GL1_3";
12"PVDDCR_CPU0_P1_VCCS";
13"SW_PVDDCR_SOC_P1_BOOT3_RC";
14"SW_P12V_AUX_PVDDCR_SOC_P1_FLT\g";
15"SW_PVDDCR_SOC_P1_SW3_RC";
16"PVDDCR_SOC_P1\g";
17"GND\g";
18"IND_SOC_P1_CPL3";
19"IND_SOC_P1_CPL0";
20"GND\g";
21"PVDDCR_CPU0_P1_PVCC\g";
22"PVDDCR_SOC_P1_IMON3";
23"PVDDCR_SOC_P1_VCC3";
24"NC_PVDDCR_SOC_P1_GL2_3";
25"GND\g";
26"NC_PVDDCR_SOC_P1_DNC3";
27"PVDDCR_SOC_P1_PWM3";
28"PVDDCR_SOC_P1_LSET3";
29"PVDDCR_SOC_P1_TEMP1";
%"Q_RES"
"2","(-4450,3775)","0","pure_quanta","I10";
;
LOCATION"PR511"
$SEC"1"
CDS_SEC"1"
MATERIAL"EMPTY"
WATTAGE"1/8W"
TOLERANCE"1%"
PACK_TYPE"0402LF"
VALUE"1.5"
CDS_LIB"pure_quanta"
PART_NUMBER"CS-1504FB00";
"A"
$PN"1"15;
"B"
$PN"2"5;
%"Q_CAP"
"1","(-4450,4300)","0","pure_quanta","I11";
;
LOCATION"PC195"
$SEC"1"
CDS_SEC"1"
TOLERANCE"10%"
MATERIAL"EMPTY"
VALUE"560PF"
VOLTAGE"50V"
PACK_TYPE"C0402"
CDS_LIB"pure_quanta"
PART_NUMBER"CH1566K1B09";
"B"
$PN"2"15;
"A"
$PN"1"9;
%"UNIVERSAL_GND"
"1","(-7350,4650)","0","pure_quanta_power","I12";
;
CDS_LIB"pure_quanta_power"
HDL_POWER"GND";
"A"1;
%"Q_CAP"
"1","(-7350,4850)","0","pure_quanta","I13";
;
LOCATION"PC346"
$SEC"1"
CDS_SEC"1"
MATERIAL"X6S"
VALUE"2.2UF"
VOLTAGE"10V"
PACK_TYPE"C0402"
TOLERANCE"10%"
CDS_LIB"pure_quanta"
PART_NUMBER"CH5222KEB01";
"B"
$PN"2"1;
"A"
$PN"1"23;
%"Q_RES"
"2","(-7350,5400)","0","pure_quanta","I14";
;
LOCATION"PR213"
$SEC"1"
CDS_SEC"1"
WATTAGE"1/16W"
TOLERANCE"1%"
VALUE"2.2"
PACK_TYPE"0402LF"
MATERIAL"CHIP"
CDS_LIB"pure_quanta"
PART_NUMBER"CS-2202FB01";
"A"
$PN"1"21;
"B"
$PN"2"23;
%"VCC_CORE"
"1","(-7350,5800)","0","pure_quanta_power","I15";
;
HDL_POWER"PVDDCR_CPU0_P1_PVCC"
CDS_LIB"pure_quanta_power";
"A"21;
%"UNIVERSAL_GND"
"1","(-7000,5150)","0","pure_quanta_power","I17";
;
CDS_LIB"pure_quanta_power"
HDL_POWER"GND";
"A"2;
%"Q_CAP"
"1","(-7000,5425)","0","pure_quanta","I18";
;
LOCATION"PC347_SOP1_3"
$SEC"1"
CDS_SEC"1"
MATERIAL"X6S"
TOLERANCE"10%"
VALUE"2.2UF"
VOLTAGE"10V"
PACK_TYPE"C0402"
CDS_LIB"pure_quanta"
PART_NUMBER"CH5222KEB01";
"B"
$PN"2"2;
"A"
$PN"1"21;
%"Q_CAP"
"1","(-5050,5375)","0","pure_quanta","I19";
;
LOCATION"PC348_3"
$SEC"1"
CDS_SEC"1"
MATERIAL"X7R"
VALUE"0.1UF"
TOLERANCE"10%"
VOLTAGE"25V"
PACK_TYPE"0402"
CDS_LIB"pure_quanta"
PART_NUMBER"CH4104K1B00";
"B"
$PN"2"6;
"A"
$PN"1"14;
%"Q_CAP"
"1","(-7675,4225)","0","pure_quanta","I2";
;
LOCATION"PC345_9"
$SEC"1"
CDS_SEC"1"
MATERIAL"X7R"
TOLERANCE"10%"
VALUE"0.1UF"
VOLTAGE"25V"
PACK_TYPE"0402"
CDS_LIB"pure_quanta"
PART_NUMBER"CH4104K1B00";
"B"
$PN"2"3;
"A"
$PN"1"12;
%"Q_CAP"
"1","(-4650,5375)","0","pure_quanta","I20";
;
LOCATION"PC349_3"
$SEC"1"
CDS_SEC"1"
MATERIAL"X6S"
VALUE"1UF"
PACK_TYPE"C0402"
TOLERANCE"10%"
VOLTAGE"25V"
CDS_LIB"pure_quanta"
PART_NUMBER"CH5104KEB02";
"B"
$PN"2"6;
"A"
$PN"1"14;
%"Q_RES"
"1","(-4475,4850)","0","pure_quanta","I21";
;
LOCATION"PR215"
$SEC"1"
CDS_SEC"1"
PACK_TYPE"0402LF"
TOLERANCE"1%"
WATTAGE"1/16W"
MATERIAL"CHIP"
VALUE"5.6"
CDS_LIB"pure_quanta"
PART_NUMBER"CS-5602FB01";
"B"
$PN"2"13;
"A"
$PN"1"7;
%"Q_CAP"
"1","(-4325,5375)","0","pure_quanta","I22";
;
LOCATION"PC350_3"
$SEC"1"
CDS_SEC"1"
PACK_TYPE"C0805"
MATERIAL"X6S"
VALUE"22UF"
VOLTAGE"16V"
TOLERANCE"20%"
CDS_LIB"pure_quanta"
PART_NUMBER"CH6223MEA01";
"B"
$PN"2"6;
"A"
$PN"1"14;
%"Q_RES"
"1","(-4000,3300)","0","pure_quanta","I23";
;
LOCATION"PR216"
$SEC"1"
CDS_SEC"1"
MATERIAL"CHIP"
PACK_TYPE"0402LF"
VALUE"0"
TOLERANCE"5%"
WATTAGE"1/16W"
CDS_LIB"pure_quanta"
PART_NUMBER"CS00002JB13";
"B"
$PN"2"16;
"A"
$PN"1"10;
%"UNIVERSAL_GND"
"1","(-3825,4150)","0","pure_quanta_power","I24";
;
CDS_LIB"pure_quanta_power"
HDL_POWER"GND";
"A"20;
%"Q_INDUCTOR"
"1","(-3650,4275)","0","pure_quanta","I25";
;
LOCATION"PL34"
$SEC"1"
CDS_SEC"1"
PACK_TYPE"SMLF"
MATERIAL"IND"
VALUE"0.22UH/33A"
NEEDS_NO_SIZE"TRUE"
CDS_LIB"pure_quanta"
PART_NUMBER"CV+22Y0EZ00";
"1"
$PN"1"20;
"2"
$PN"2"19;
%"Q_INDUCTOR4P_14"
"1","(-2650,4375)","0","pure_quanta","I26";
;
LOCATION"PL38"
$SEC"1"
CDS_SEC"1"
PART_TYPE"SMLF"
MATERIAL"IND"
VALUE"150NH"
CDS_LIB"pure_quanta"
NEEDS_NO_SIZE"TRUE"
PART_NUMBER"CV+15^0TZ04";
"1"
$PN"1"9;
"4"
$PN"4"16;
"3"
$PN"3"18;
"2"
$PN"2"19;
%"Q_CAP"
"1","(-1425,4325)","0","pure_quanta","I28";
;
LOCATION"PC354_3"
$SEC"1"
CDS_SEC"1"
VOLTAGE"4V"
VALUE"22UF"
TOLERANCE"20%"
MATERIAL"X6S"
PACK_TYPE"C0805"
CDS_LIB"pure_quanta"
PART_NUMBER"CH622KMEA03";
"B"
$PN"2"17;
"A"
$PN"1"16;
%"UNIVERSAL_GND"
"1","(-1000,3975)","0","pure_quanta_power","I29";
;
CDS_LIB"pure_quanta_power"
HDL_POWER"GND";
"A"17;
%"UNIVERSAL_GND"
"1","(-7675,3950)","0","pure_quanta_power","I3";
;
CDS_LIB"pure_quanta_power"
HDL_POWER"GND";
"A"3;
%"Q_CAP"
"1","(-1000,4325)","0","pure_quanta","I30";
;
LOCATION"PC355_3"
$SEC"1"
CDS_SEC"1"
VOLTAGE"4V"
VALUE"22UF"
TOLERANCE"20%"
MATERIAL"X6S"
PACK_TYPE"C0805"
CDS_LIB"pure_quanta"
PART_NUMBER"CH622KMEA03";
"B"
$PN"2"17;
"A"
$PN"1"16;
%"Q_CAP"
"1","(-4000,5375)","0","pure_quanta","I31";
;
LOCATION"PC351_3"
$SEC"1"
CDS_SEC"1"
PACK_TYPE"C0805"
VALUE"22UF"
MATERIAL"X6S"
VOLTAGE"16V"
TOLERANCE"20%"
CDS_LIB"pure_quanta"
PART_NUMBER"CH6223MEA01";
"B"
$PN"2"6;
"A"
$PN"1"14;
%"Q_CAP"
"1","(-3700,5375)","0","pure_quanta","I32";
;
LOCATION"PC352_3"
$SEC"1"
CDS_SEC"1"
PACK_TYPE"C0805"
MATERIAL"X6S"
VALUE"22UF"
VOLTAGE"16V"
TOLERANCE"20%"
CDS_LIB"pure_quanta"
PART_NUMBER"CH6223MEA01";
"B"
$PN"2"6;
"A"
$PN"1"14;
%"Q_CAP"
"1","(-3500,4725)","0","pure_quanta","I33";
;
LOCATION"PC353"
$SEC"1"
CDS_SEC"1"
MATERIAL"X7R"
TOLERANCE"10%"
VALUE"0.22UF"
VOLTAGE"16V"
PACK_TYPE"0402"
CDS_LIB"pure_quanta"
PART_NUMBER"CH4223K1B00";
"B"
$PN"2"8;
"A"
$PN"1"13;
%"Q_CAP"
"1","(-3325,5375)","0","pure_quanta","I34";
;
LOCATION"PC353_3"
$SEC"1"
CDS_SEC"1"
MATERIAL"X6S"
TOLERANCE"20%"
PACK_TYPE"C0805"
VALUE"22UF"
VOLTAGE"16V"
CDS_LIB"pure_quanta"
PART_NUMBER"CH6223MEA01";
"B"
$PN"2"6;
"A"
$PN"1"14;
%"UNIVERSAL_GND"
"1","(-3325,5050)","0","pure_quanta_power","I35";
;
CDS_LIB"pure_quanta_power"
HDL_POWER"GND";
"A"6;
%"VCC_CORE"
"1","(-3325,5650)","0","pure_quanta_power","I36";
;
HDL_POWER"SW_P12V_AUX_PVDDCR_SOC_P1_FLT"
CDS_LIB"pure_quanta_power";
"A"14;
%"VCC_CORE"
"1","(-1000,4650)","0","pure_quanta_power","I37";
;
HDL_POWER"PVDDCR_SOC_P1"
CDS_LIB"pure_quanta_power";
"A"16;
%"ISL99390FRZTR5935"
"1","(-5850,4500)","0","pure_quanta","I38";
;
LOCATION"PU32"
$SEC"1"
CDS_SEC"1"
PART_TYPE"SMLF"
VALUE"ISL99390FRZ-TR5935"
MATERIAL"IC"
CDS_LIB"pure_quanta"
CDS_LMAN_SYM_OUTLINE"-300,700,250,-650"
NEEDS_NO_SIZE"TRUE"
PART_NUMBER"AL099390004";
"PGND2"
$PN"7_9-20_24"25;
"GL2"
$PN"41"24;
"GL1"
$PN"6"11;
"DNC"
$PN"31"26;
"EN"
$PN"35"23;
"PGND3"
$PN"40"25;
"VOS"
$PN"1"10;
"VIN2"
$PN"30"14;
"PGND1"
$PN"5"25;
"SW"
$PN"10_19"9;
"LSET"
$PN"37"28;
"IOUT"
$PN"38"22;
"TOUT_FLT"
$PN"36"29;
"PVCC"
$PN"4"21;
"PHASE"
$PN"32"8;
"VIN1"
$PN"25_29"14;
"BOOT"
$PN"33"7;
"AGND"
$PN"2"25;
"VCC"
$PN"3"23;
"REFIN"
$PN"39"12;
"PWM"
$PN"34"27;
%"UNIVERSAL_GND"
"1","(-7325,4025)","0","pure_quanta_power","I4";
;
CDS_LIB"pure_quanta_power"
HDL_POWER"GND";
"A"4;
%"Q_RES"
"1","(-7000,4200)","0","pure_quanta","I7";
;
LOCATION"PR214"
$SEC"1"
CDS_SEC"1"
MATERIAL"EMPTY"
TOLERANCE"1%"
VALUE"8.87K"
PACK_TYPE"0402LF"
WATTAGE"1/16W"
CDS_LIB"pure_quanta"
PART_NUMBER"CS28872FB01";
"B"
$PN"2"28;
"A"
$PN"1"4;
%"UNIVERSAL_GND"
"1","(-5275,3775)","0","pure_quanta_power","I8";
;
CDS_LIB"pure_quanta_power"
HDL_POWER"GND";
"A"25;
%"UNIVERSAL_GND"
"1","(-4450,3550)","0","pure_quanta_power","I9";
;
CDS_LIB"pure_quanta_power"
HDL_POWER"GND";
"A"5;
END.
